(kicad_pcb
	(version 20211014)
	(generator pcbnew)
	(general
    (thickness 1.6)
  )
	(paper "A4")
	(title_block
    (title "SA800U (Snapdragon 845) Baseboard")
    (date "2023-10-19")
    (rev "1.0.3")
    (company "Antmicro Ltd.")
    (comment 1 "www.antmicro.com")
		(comment 9 "footprint 58 of 589 (U11), pads 290-348 of 348")
	)
	(layers
    (0 "F.Cu" signal)
    (1 "In1.Cu" power)
    (2 "In2.Cu" signal)
    (3 "In3.Cu" signal)
    (4 "In4.Cu" power)
    (31 "B.Cu" signal)
    (32 "B.Adhes" user "B.Adhesive")
    (33 "F.Adhes" user "F.Adhesive")
    (34 "B.Paste" user)
    (35 "F.Paste" user)
    (36 "B.SilkS" user "B.Silkscreen")
    (37 "F.SilkS" user "F.Silkscreen")
    (38 "B.Mask" user)
    (39 "F.Mask" user)
    (40 "Dwgs.User" user "User.Drawings")
    (41 "Cmts.User" user "User.Comments")
    (42 "Eco1.User" user "User.Eco1")
    (43 "Eco2.User" user "User.Eco2")
    (44 "Edge.Cuts" user)
    (45 "Margin" user)
    (46 "B.CrtYd" user "B.Courtyard")
    (47 "F.CrtYd" user "F.Courtyard")
    (48 "B.Fab" user)
    (49 "F.Fab" user)
  )
	(footprint "sa800u-baseboard-hw-footprints:Receptacle_SA800U-WF" locked
    (layer "F.Cu")
    (tedit 6215E1EF)
    (at 112.47 100.96)
    (property "Author" "Antmicro")
    (property "License" "Apache-2.0")
    (property "MPN" "FX10A-168S-SV")
    (property "Manufacturer" "Hirose Electric")
    (property "Sheetfile" "som.kicad_sch")
    (property "Sheetname" "SoM")
    (attr smd)
    (fp_text reference "U11" (at 0.005 -19.31) (layer "F.SilkS")
      (effects (font (size 0.7 0.7) (thickness 0.15)) (justify left bottom))
    )
    (fp_text value "Receptacle_SA800U-WF" (at 0 20.4) (layer "F.Fab")
      (effects (font (size 0.7 0.7) (thickness 0.15)) (justify left bottom))
    )
    (pad "2_112" smd rect locked (at -7.741 11.473 180) (size 0.33 1.6) (layers "F.Cu" "F.Paste" "F.Mask")
      (net 68 "USB1_SS_RX1_P") (pinfunction "USB1_SS2_RX_P") (pintype "input"))
    (pad "2_113" smd rect locked (at -8.241 17.573 180) (size 0.33 1.6) (layers "F.Cu" "F.Paste" "F.Mask")
      (net 72 "USB1_SS_TX1_P") (pinfunction "USB1_SS2_TX_P") (pintype "output"))
    (pad "2_114" smd rect locked (at -8.241 11.473 180) (size 0.33 1.6) (layers "F.Cu" "F.Paste" "F.Mask")
      (net 67 "USB1_SS_RX1_N") (pinfunction "USB1_SS2_RX_M") (pintype "input"))
    (pad "2_115" smd rect locked (at -8.741 17.573 180) (size 0.33 1.6) (layers "F.Cu" "F.Paste" "F.Mask")
      (net 1 "GND") (pinfunction "GND") (pintype "passive"))
    (pad "2_116" smd rect locked (at -8.741 11.473 180) (size 0.33 1.6) (layers "F.Cu" "F.Paste" "F.Mask")
      (net 1 "GND") (pinfunction "GND") (pintype "passive"))
    (pad "2_117" smd rect locked (at -9.241 17.573 180) (size 0.33 1.6) (layers "F.Cu" "F.Paste" "F.Mask")
      (net 322 "USB1_D_N") (pinfunction "USB1_DM") (pintype "bidirectional"))
    (pad "2_118" smd rect locked (at -9.241 11.473 180) (size 0.33 1.6) (layers "F.Cu" "F.Paste" "F.Mask")
      (net 70 "USB1_SS_RX0_N") (pinfunction "USB1_SS1_RX_M") (pintype "input"))
    (pad "2_119" smd rect locked (at -9.741 17.573 180) (size 0.33 1.6) (layers "F.Cu" "F.Paste" "F.Mask")
      (net 321 "USB1_D_P") (pinfunction "USB1_DP") (pintype "bidirectional"))
    (pad "2_120" smd rect locked (at -9.741 11.473 180) (size 0.33 1.6) (layers "F.Cu" "F.Paste" "F.Mask")
      (net 69 "USB1_SS_RX0_P") (pinfunction "USB1_SS1_RX_P") (pintype "input"))
    (pad "2_121" smd rect locked (at -10.24 17.573 180) (size 0.33 1.6) (layers "F.Cu" "F.Paste" "F.Mask")
      (net 1 "GND") (pinfunction "GND") (pintype "passive"))
    (pad "2_122" smd rect locked (at -10.24 11.473 180) (size 0.33 1.6) (layers "F.Cu" "F.Paste" "F.Mask")
      (net 1 "GND") (pinfunction "GND") (pintype "passive"))
    (pad "2_123" smd rect locked (at -10.74 17.573 180) (size 0.33 1.6) (layers "F.Cu" "F.Paste" "F.Mask")
      (net 65 "USB1_SS_TX0_N") (pinfunction "USB1_SS1_TX_M") (pintype "output"))
    (pad "2_124" smd rect locked (at -10.74 11.473 180) (size 0.33 1.6) (layers "F.Cu" "F.Paste" "F.Mask")
      (net 132 "VREG_S4A_1V8") (pinfunction "VREG_S4A_1V8") (pintype "power_in"))
    (pad "2_125" smd rect locked (at -11.24 17.573 180) (size 0.33 1.6) (layers "F.Cu" "F.Paste" "F.Mask")
      (net 64 "USB1_SS_TX0_P") (pinfunction "USB1_SS1_TX_P") (pintype "output"))
    (pad "2_126" smd rect locked (at -11.24 11.473 180) (size 0.33 1.6) (layers "F.Cu" "F.Paste" "F.Mask")
      (net 132 "VREG_S4A_1V8") (pinfunction "VREG_S4A_1V8") (pintype "passive"))
    (pad "2_127" smd rect locked (at -11.74 17.573 180) (size 0.33 1.6) (layers "F.Cu" "F.Paste" "F.Mask")
      (net 1 "GND") (pinfunction "GND") (pintype "passive"))
    (pad "2_128" smd rect locked (at -11.74 11.473 180) (size 0.33 1.6) (layers "F.Cu" "F.Paste" "F.Mask")
      (net 132 "VREG_S4A_1V8") (pinfunction "VREG_S4A_1V8") (pintype "passive"))
    (pad "2_129" smd rect locked (at -12.24 17.573 180) (size 0.33 1.6) (layers "F.Cu" "F.Paste" "F.Mask")
      (net 11 "EDP_AUX_P") (pinfunction "EDP_AUX_P") (pintype "bidirectional"))
    (pad "2_130" smd rect locked (at -12.24 11.473 180) (size 0.33 1.6) (layers "F.Cu" "F.Paste" "F.Mask")
      (net 418 "/SoM/USB_BOOT") (pinfunction "USB_BOOT") (pintype "input"))
    (pad "2_131" smd rect locked (at -12.74 17.573 180) (size 0.33 1.6) (layers "F.Cu" "F.Paste" "F.Mask")
      (net 10 "EDP_AUX_N") (pinfunction "EDP_AUX_N") (pintype "bidirectional"))
    (pad "2_132" smd rect locked (at -12.74 11.473 180) (size 0.33 1.6) (layers "F.Cu" "F.Paste" "F.Mask")
      (net 320 "1V2_SYS_EN") (pinfunction "GPIO_128") (pintype "bidirectional"))
    (pad "2_133" smd rect locked (at -13.24 17.573 180) (size 0.33 1.6) (layers "F.Cu" "F.Paste" "F.Mask")
      (net 336 "/SoM/VRTC") (pinfunction "VRTC") (pintype "bidirectional"))
    (pad "2_134" smd rect locked (at -13.24 11.473 180) (size 0.33 1.6) (layers "F.Cu" "F.Paste" "F.Mask")
      (net 319 "3V3_SYS_EN") (pinfunction "GPIO_135") (pintype "bidirectional"))
    (pad "2_135" smd rect locked (at -13.74 17.573 180) (size 0.33 1.6) (layers "F.Cu" "F.Paste" "F.Mask")
      (net 129 "DBG_RXD") (pinfunction "DBG_RXD") (pintype "input"))
    (pad "2_136" smd rect locked (at -13.74 11.473 180) (size 0.33 1.6) (layers "F.Cu" "F.Paste" "F.Mask")
      (net 349 "/SoM/BOOT") (pinfunction "GPIO_129") (pintype "bidirectional"))
    (pad "2_137" smd rect locked (at -14.24 17.573 180) (size 0.33 1.6) (layers "F.Cu" "F.Paste" "F.Mask")
      (net 130 "DBG_TXD") (pinfunction "DBG_TXD") (pintype "output"))
    (pad "2_138" smd rect locked (at -14.24 11.473 180) (size 0.33 1.6) (layers "F.Cu" "F.Paste" "F.Mask")
      (net 522 "unconnected-(U11-Pad2_138)") (pinfunction "RESERVED1") (pintype "no_connect"))
    (pad "2_139" smd rect locked (at -14.74 17.573 180) (size 0.33 1.6) (layers "F.Cu" "F.Paste" "F.Mask")
      (net 327 "USB_CC2") (pinfunction "USB_CC2") (pintype "input"))
    (pad "2_140" smd rect locked (at -14.74 11.473 180) (size 0.33 1.6) (layers "F.Cu" "F.Paste" "F.Mask")
      (net 521 "unconnected-(U11-Pad2_140)") (pinfunction "VREG_BOB2") (pintype "power_in+no_connect"))
    (pad "2_141" smd rect locked (at -15.24 17.573 180) (size 0.33 1.6) (layers "F.Cu" "F.Paste" "F.Mask")
      (net 326 "USB_CC1") (pinfunction "USB_CC1") (pintype "input"))
    (pad "2_142" smd rect locked (at -15.24 11.473 180) (size 0.33 1.6) (layers "F.Cu" "F.Paste" "F.Mask")
      (net 520 "unconnected-(U11-Pad2_142)") (pinfunction "VREG_BOB1") (pintype "power_in+no_connect"))
    (pad "2_143" smd rect locked (at -15.74 17.573 180) (size 0.33 1.6) (layers "F.Cu" "F.Paste" "F.Mask")
      (net 398 "Net-(R70-Pad1)") (pinfunction "BAT_THERM") (pintype "input"))
    (pad "2_144" smd rect locked (at -15.74 11.473 180) (size 0.33 1.6) (layers "F.Cu" "F.Paste" "F.Mask")
      (net 519 "unconnected-(U11-Pad2_144)") (pinfunction "PWM_PMI_GPIO8") (pintype "output+no_connect"))
    (pad "2_145" smd rect locked (at -16.24 17.573 180) (size 0.33 1.6) (layers "F.Cu" "F.Paste" "F.Mask")
      (net 94 "HOME_KEY") (pinfunction "HOME_KEY") (pintype "input"))
    (pad "2_146" smd rect locked (at -16.24 11.473 180) (size 0.33 1.6) (layers "F.Cu" "F.Paste" "F.Mask")
      (net 518 "unconnected-(U11-Pad2_146)") (pinfunction "PWM_PMI_GPIO5") (pintype "output+no_connect"))
    (pad "2_147" smd rect locked (at -16.74 17.573 180) (size 0.33 1.6) (layers "F.Cu" "F.Paste" "F.Mask")
      (net 517 "unconnected-(U11-Pad2_147)") (pinfunction "PMU_GPIO10") (pintype "bidirectional+no_connect"))
    (pad "2_148" smd rect locked (at -16.74 11.473 180) (size 0.33 1.6) (layers "F.Cu" "F.Paste" "F.Mask")
      (net 516 "LVS2A_1V8") (pinfunction "LVS2A_1V8") (pintype "power_in"))
    (pad "2_149" smd rect locked (at -17.24 17.573 180) (size 0.33 1.6) (layers "F.Cu" "F.Paste" "F.Mask")
      (net 515 "unconnected-(U11-Pad2_149)") (pinfunction "PMU_GPIO13") (pintype "bidirectional+no_connect"))
    (pad "2_150" smd rect locked (at -17.24 11.473 180) (size 0.33 1.6) (layers "F.Cu" "F.Paste" "F.Mask")
      (net 514 "LDO19A_3V0") (pinfunction "LDO19A_3V0") (pintype "power_in"))
    (pad "2_151" smd rect locked (at -17.74 17.573 180) (size 0.33 1.6) (layers "F.Cu" "F.Paste" "F.Mask")
      (net 513 "unconnected-(U11-Pad2_151)") (pinfunction "ADC_PMU_GPIO21") (pintype "output+no_connect"))
    (pad "2_152" smd rect locked (at -17.74 11.473 180) (size 0.33 1.6) (layers "F.Cu" "F.Paste" "F.Mask")
      (net 512 "unconnected-(U11-Pad2_152)") (pinfunction "R_LED") (pintype "output+no_connect"))
    (pad "2_153" smd rect locked (at -18.24 17.573 180) (size 0.33 1.6) (layers "F.Cu" "F.Paste" "F.Mask")
      (net 511 "unconnected-(U11-Pad2_153)") (pinfunction "ADC_PMU_GPIO8") (pintype "output+no_connect"))
    (pad "2_154" smd rect locked (at -18.24 11.473 180) (size 0.33 1.6) (layers "F.Cu" "F.Paste" "F.Mask")
      (net 510 "unconnected-(U11-Pad2_154)") (pinfunction "B_LED") (pintype "output+no_connect"))
    (pad "2_155" smd rect locked (at -18.74 17.573 180) (size 0.33 1.6) (layers "F.Cu" "F.Paste" "F.Mask")
      (net 1 "GND") (pinfunction "GND") (pintype "passive"))
    (pad "2_156" smd rect locked (at -18.74 11.473 180) (size 0.33 1.6) (layers "F.Cu" "F.Paste" "F.Mask")
      (net 509 "unconnected-(U11-Pad2_156)") (pinfunction "G_LED") (pintype "output+no_connect"))
    (pad "2_157" smd rect locked (at -19.24 17.573 180) (size 0.33 1.6) (layers "F.Cu" "F.Paste" "F.Mask")
      (net 420 "Net-(R176-Pad1)") (pinfunction "CS_P") (pintype "input"))
    (pad "2_158" smd rect locked (at -19.24 11.473 180) (size 0.33 1.6) (layers "F.Cu" "F.Paste" "F.Mask")
      (net 1 "GND") (pinfunction "GND") (pintype "passive"))
    (pad "2_159" smd rect locked (at -19.74 17.573 180) (size 0.33 1.6) (layers "F.Cu" "F.Paste" "F.Mask")
      (net 421 "Net-(R177-Pad1)") (pinfunction "CS_M") (pintype "input"))
    (pad "2_160" smd rect locked (at -19.74 11.473 180) (size 0.33 1.6) (layers "F.Cu" "F.Paste" "F.Mask")
      (net 66 "USB_VBUS") (pinfunction "USB_VBUS") (pintype "power_in"))
    (pad "2_161" smd rect locked (at -20.24 17.573 180) (size 0.33 1.6) (layers "F.Cu" "F.Paste" "F.Mask")
      (net 1 "GND") (pinfunction "GND") (pintype "passive"))
    (pad "2_162" smd rect locked (at -20.24 11.473 180) (size 0.33 1.6) (layers "F.Cu" "F.Paste" "F.Mask")
      (net 66 "USB_VBUS") (pinfunction "USB_VBUS") (pintype "passive"))
    (pad "2_163" smd rect locked (at -20.74 17.573 180) (size 0.33 1.6) (layers "F.Cu" "F.Paste" "F.Mask")
      (net 422 "Net-(R178-Pad1)") (pinfunction "BAT_P") (pintype "input"))
    (pad "2_164" smd rect locked (at -20.74 11.473 180) (size 0.33 1.6) (layers "F.Cu" "F.Paste" "F.Mask")
      (net 66 "USB_VBUS") (pinfunction "USB_VBUS") (pintype "passive"))
    (pad "2_165" smd rect locked (at -21.24 17.573 180) (size 0.33 1.6) (layers "F.Cu" "F.Paste" "F.Mask")
      (net 423 "Net-(R179-Pad1)") (pinfunction "BAT_M") (pintype "input"))
    (pad "2_166" smd rect locked (at -21.24 11.473 180) (size 0.33 1.6) (layers "F.Cu" "F.Paste" "F.Mask")
      (net 66 "USB_VBUS") (pinfunction "USB_VBUS") (pintype "passive"))
    (pad "2_167" smd rect locked (at -21.74 17.573 180) (size 0.33 1.6) (layers "F.Cu" "F.Paste" "F.Mask")
      (net 1 "GND") (pinfunction "GND") (pintype "passive"))
    (pad "2_168" smd rect locked (at -21.74 11.473 180) (size 0.33 1.6) (layers "F.Cu" "F.Paste" "F.Mask")
      (net 66 "USB_VBUS") (pinfunction "USB_VBUS") (pintype "passive"))
    (pad "2_171" smd rect locked (at 22.961 14.524 270) (size 3.2 1.6) (layers "F.Cu" "F.Paste" "F.Mask")
      (net 508 "unconnected-(U11-Pad2_171)") (pinfunction "NC") (pintype "no_connect"))
    (pad "2_172" smd rect locked (at -24.939 14.524 270) (size 3.2 1.6) (layers "F.Cu" "F.Paste" "F.Mask")
      (net 507 "unconnected-(U11-Pad2_172)") (pinfunction "NC") (pintype "no_connect"))
  )
)
